(kicad_pcb
	(version 20260206)
	(generator "pcbnew")
	(generator_version "10.0")
	(general
		(thickness 1.6)
		(legacy_teardrops no)
	)
	(paper "A4")
	(title_block
		(title "timecard-production-celestica-r4006 — R4006-B0001-02_R01.brd")
		(comment 1 "Time Appliance Project (Time Card) / footprints 1070-1074 of 1113")
	)
	(layers
		(0 "F.Cu" signal "TOP")
		(4 "In1.Cu" signal "L02_GND1")
		(6 "In2.Cu" signal "L03_SIG1")
		(8 "In3.Cu" signal "L04_GND2")
		(10 "In4.Cu" signal "L05_VCC1")
		(12 "In5.Cu" signal "L06_VCC2")
		(14 "In6.Cu" signal "L07_GND3")
		(16 "In7.Cu" signal "L08_SIG2")
		(18 "In8.Cu" signal "L09_GND4")
		(2 "B.Cu" signal "BOTTOM")
		(9 "F.Adhes" user "F.Adhesive")
		(11 "B.Adhes" user "B.Adhesive")
		(13 "F.Paste" user "Package Geometry/Pastemask Top")
		(15 "B.Paste" user "Package Geometry/Pastemask Bottom")
		(5 "F.SilkS" user "Ref Des/Silkscreen Top")
		(7 "B.SilkS" user "Ref Des/Silkscreen Bottom")
		(1 "F.Mask" user "Board Geometry/Soldermask Top")
		(3 "B.Mask" user "Board Geometry/Soldermask Bottom")
		(17 "Dwgs.User" user "User.Drawings")
		(19 "Cmts.User" user "User.Comments")
		(21 "Eco1.User" user "User.Eco1")
		(23 "Eco2.User" user "User.Eco2")
		(25 "Edge.Cuts" user "Board Geometry/Outline")
		(27 "Margin" user)
		(31 "F.CrtYd" user "Package Geometry/Place Bound Top")
		(29 "B.CrtYd" user "Package Geometry/Place Bound Bottom")
		(35 "F.Fab" user "Ref Des/Assembly Top")
		(33 "B.Fab" user "Ref Des/Assembly Bottom")
	)
	(footprint ""
		(layer "B.Cu")
		(at 77.089 -73.152 -90)
		(property "Reference" "C282"
			(at -3.556 0.03937 270)
			(unlocked yes)
			(layer "B.SilkS")
			(effects
				(font
					(size 0.7874 0.5842)
					(thickness 0.1524)
				)
				(justify mirror)
			)
		)
		(property "Value" "VAL*"
			(at -0.0762 3.134106 270)
			(unlocked yes)
			(layer "B.Fab")
			(hide yes)
			(effects
				(font
					(size 0.7874 0.5842)
					(thickness 0.1524)
				)
				(justify mirror)
			)
		)
		(property "Device Type" "CAPACITOR-G107-0F106-EM,10UF,2A"
			(at -0.0508 2.194306 270)
			(unlocked yes)
			(layer "B.Fab")
			(hide yes)
			(effects
				(font
					(size 0.7874 0.5842)
					(thickness 0.1524)
				)
				(justify mirror)
			)
		)
		(property "User Part Number" "PARTNUM*"
			(at -0.1016 5.013706 270)
			(unlocked yes)
			(layer "Cmts.User")
			(hide yes)
			(effects
				(font
					(size 0.7874 0.5842)
					(thickness 0.1524)
				)
				(justify mirror)
			)
		)
		(property "Tolerance" "TOL*"
			(at -0.0762 4.048506 270)
			(unlocked yes)
			(layer "Cmts.User")
			(hide yes)
			(effects
				(font
					(size 0.7874 0.5842)
					(thickness 0.1524)
				)
				(justify mirror)
			)
		)
		(duplicate_pad_numbers_are_jumpers no)
		(fp_line
			(start -1.5748 0.9398)
			(end -1.5748 -0.9398)
			(stroke
				(width 0.1)
				(type default)
			)
			(layer "B.SilkS")
		)
		(fp_line
			(start 1.5748 0.9398)
			(end -1.5748 0.9398)
			(stroke
				(width 0.1)
				(type default)
			)
			(layer "B.SilkS")
		)
		(fp_line
			(start -1.5748 -0.9398)
			(end 1.5748 -0.9398)
			(stroke
				(width 0.1)
				(type default)
			)
			(layer "B.SilkS")
		)
		(fp_line
			(start 1.5748 -0.9398)
			(end 1.5748 0.9398)
			(stroke
				(width 0.1)
				(type default)
			)
			(layer "B.SilkS")
		)
		(fp_rect
			(start 1.5748 -0.9398)
			(end -1.5748 0.9398)
			(stroke
				(width 0)
				(type default)
			)
			(fill no)
			(layer "B.CrtYd")
		)
		(fp_line
			(start -1.016 0.635)
			(end -1.016 -0.635)
			(stroke
				(width 0.1)
				(type default)
			)
			(layer "B.Fab")
		)
		(fp_line
			(start 1.016 0.635)
			(end -1.016 0.635)
			(stroke
				(width 0.1)
				(type default)
			)
			(layer "B.Fab")
		)
		(fp_line
			(start -1.016 -0.635)
			(end 1.016 -0.635)
			(stroke
				(width 0.1)
				(type default)
			)
			(layer "B.Fab")
		)
		(fp_line
			(start 1.016 -0.635)
			(end 1.016 0.635)
			(stroke
				(width 0.1)
				(type default)
			)
			(layer "B.Fab")
		)
		(pad "1" smd rect
			(at 0.8382 0 90)
			(size 0.9652 1.3716)
			(layers "B.Cu" "B.Mask" "B.Paste")
			(net "XP5R0V_MAC")
		)
		(pad "2" smd rect
			(at -0.8382 0 90)
			(size 0.9652 1.3716)
			(layers "B.Cu" "B.Mask" "B.Paste")
			(net "SG")
		)
		(zone
			(layer "B.Cu")
			(hatch none 0.5)
			(connect_pads
				(clearance 0)
			)
			(min_thickness 0.25)
			(keepout
				(tracks allowed)
				(vias not_allowed)
				(pads allowed)
				(copperpour not_allowed)
				(footprints allowed)
			)
			(placement
				(enabled no)
				(sheetname "")
			)
			(fill
				(thermal_gap 0.5)
				(thermal_bridge_width 0.5)
				(island_removal_mode 0)
			)
			(polygon
				(pts
					(xy 77.724 -72.9234) (xy 77.724 -73.3806) (xy 76.454 -73.3806) (xy 76.454 -72.9234)
				)
			)
		)
	)
	(footprint ""
		(layer "B.Cu")
		(at 138.4808 -77.216 90)
		(property "Reference" "R405"
			(at 1.778 -1.10617 270)
			(unlocked yes)
			(layer "B.SilkS")
			(effects
				(font
					(size 0.7874 0.5842)
					(thickness 0.1524)
				)
				(justify mirror)
			)
		)
		(property "Value" "VAL*"
			(at -0.02032 2.13233 90)
			(unlocked yes)
			(layer "B.Fab")
			(hide yes)
			(effects
				(font
					(size 0.7874 0.5842)
					(thickness 0.1524)
				)
				(justify mirror)
			)
		)
		(property "Device Type" "RESISTOR-G155-11002-01,10KOHM,A"
			(at -0.008382 1.210564 90)
			(unlocked yes)
			(layer "B.Fab")
			(hide yes)
			(effects
				(font
					(size 0.7874 0.5842)
					(thickness 0.1524)
				)
				(justify mirror)
			)
		)
		(property "User Part Number" "PARTNUM*"
			(at -0.02032 4.024884 90)
			(unlocked yes)
			(layer "Cmts.User")
			(hide yes)
			(effects
				(font
					(size 0.7874 0.5842)
					(thickness 0.1524)
				)
				(justify mirror)
			)
		)
		(property "Tolerance" "TOL*"
			(at -0.044704 3.05435 90)
			(unlocked yes)
			(layer "Cmts.User")
			(hide yes)
			(effects
				(font
					(size 0.7874 0.5842)
					(thickness 0.1524)
				)
				(justify mirror)
			)
		)
		(duplicate_pad_numbers_are_jumpers no)
		(fp_line
			(start 1.143 -0.5588)
			(end 1.143 0.5588)
			(stroke
				(width 0.1)
				(type default)
			)
			(layer "B.SilkS")
		)
		(fp_line
			(start -1.143 -0.5588)
			(end 1.143 -0.5588)
			(stroke
				(width 0.1)
				(type default)
			)
			(layer "B.SilkS")
		)
		(fp_line
			(start 1.143 0.5588)
			(end -1.143 0.5588)
			(stroke
				(width 0.1)
				(type default)
			)
			(layer "B.SilkS")
		)
		(fp_line
			(start -1.143 0.5588)
			(end -1.143 -0.5588)
			(stroke
				(width 0.1)
				(type default)
			)
			(layer "B.SilkS")
		)
		(fp_rect
			(start 1.143 0.5588)
			(end -1.143 -0.5588)
			(stroke
				(width 0)
				(type default)
			)
			(fill no)
			(layer "B.CrtYd")
		)
		(fp_line
			(start 0.508 -0.3048)
			(end 0.508 0.3048)
			(stroke
				(width 0.1)
				(type default)
			)
			(layer "B.Fab")
		)
		(fp_line
			(start -0.508 -0.3048)
			(end 0.508 -0.3048)
			(stroke
				(width 0.1)
				(type default)
			)
			(layer "B.Fab")
		)
		(fp_line
			(start 0.508 0.3048)
			(end -0.508 0.3048)
			(stroke
				(width 0.1)
				(type default)
			)
			(layer "B.Fab")
		)
		(fp_line
			(start -0.508 0.3048)
			(end -0.508 -0.3048)
			(stroke
				(width 0.1)
				(type default)
			)
			(layer "B.Fab")
		)
		(pad "1" smd rect
			(at 0.5334 0 270)
			(size 0.7112 0.6096)
			(layers "B.Cu" "B.Mask" "B.Paste")
			(net "XP3R3V_FPGA")
		)
		(pad "2" smd rect
			(at -0.5334 0 270)
			(size 0.7112 0.6096)
			(layers "B.Cu" "B.Mask" "B.Paste")
			(net "FPGA_TDI")
		)
		(zone
			(layer "B.Cu")
			(hatch none 0.5)
			(connect_pads
				(clearance 0)
			)
			(min_thickness 0.25)
			(keepout
				(tracks not_allowed)
				(vias allowed)
				(pads allowed)
				(copperpour not_allowed)
				(footprints allowed)
			)
			(placement
				(enabled no)
				(sheetname "")
			)
			(fill
				(thermal_gap 0.5)
				(thermal_bridge_width 0.5)
				(island_removal_mode 0)
			)
			(polygon
				(pts
					(xy 138.7856 -77.2922) (xy 138.176 -77.2922) (xy 138.176 -77.1398) (xy 138.7856 -77.1398)
				)
			)
		)
		(zone
			(layer "B.Cu")
			(hatch none 0.5)
			(connect_pads
				(clearance 0)
			)
			(min_thickness 0.25)
			(keepout
				(tracks allowed)
				(vias not_allowed)
				(pads allowed)
				(copperpour not_allowed)
				(footprints allowed)
			)
			(placement
				(enabled no)
				(sheetname "")
			)
			(fill
				(thermal_gap 0.5)
				(thermal_bridge_width 0.5)
				(island_removal_mode 0)
			)
			(polygon
				(pts
					(xy 138.7856 -77.2922) (xy 138.176 -77.2922) (xy 138.176 -77.1398) (xy 138.7856 -77.1398)
				)
			)
		)
	)
	(footprint ""
		(layer "B.Cu")
		(at 99.846892 -53.322982 90)
		(property "Reference" "C140"
			(at 1.414018 1.086358 270)
			(unlocked yes)
			(layer "B.SilkS")
			(effects
				(font
					(size 0.635 0.4064)
					(thickness 0.1524)
				)
				(justify mirror)
			)
		)
		(property "Value" "VAL*"
			(at 0 3.718306 90)
			(unlocked yes)
			(layer "B.Fab")
			(hide yes)
			(effects
				(font
					(size 0.7874 0.5842)
					(thickness 0.127)
				)
				(justify mirror)
			)
		)
		(property "Tolerance" "TOL*"
			(at 0 4.861306 90)
			(unlocked yes)
			(layer "Cmts.User")
			(hide yes)
			(effects
				(font
					(size 0.7874 0.5842)
					(thickness 0.127)
				)
				(justify mirror)
			)
		)
		(property "User Part Number" "PARTNUM*"
			(at 0 2.575306 90)
			(unlocked yes)
			(layer "Cmts.User")
			(hide yes)
			(effects
				(font
					(size 0.7874 0.5842)
					(thickness 0.127)
				)
				(justify mirror)
			)
		)
		(property "Device Type" "CAPACITOR-G105-0B104-CK,0.1UF,A"
			(at 0 1.432306 90)
			(unlocked yes)
			(layer "B.Fab")
			(hide yes)
			(effects
				(font
					(size 0.7874 0.5842)
					(thickness 0.127)
				)
				(justify mirror)
			)
		)
		(duplicate_pad_numbers_are_jumpers no)
		(fp_line
			(start 0.970026 -0.4699)
			(end -0.970026 -0.4699)
			(stroke
				(width 0.1)
				(type default)
			)
			(layer "B.SilkS")
		)
		(fp_line
			(start -0.970026 -0.4699)
			(end -0.970026 0.4699)
			(stroke
				(width 0.1)
				(type default)
			)
			(layer "B.SilkS")
		)
		(fp_line
			(start 0.970026 0.4699)
			(end 0.970026 -0.4699)
			(stroke
				(width 0.1)
				(type default)
			)
			(layer "B.SilkS")
		)
		(fp_line
			(start -0.970026 0.4699)
			(end 0.970026 0.4699)
			(stroke
				(width 0.1)
				(type default)
			)
			(layer "B.SilkS")
		)
		(fp_poly
			(pts
				(xy 0.970026 0.4699) (xy -0.970026 0.4699) (xy -0.970026 -0.4699) (xy 0.970026 -0.4699)
			)
			(stroke
				(width 0)
				(type default)
			)
			(fill no)
			(layer "B.CrtYd")
		)
		(fp_line
			(start 0.508 -0.3048)
			(end -0.508 -0.3048)
			(stroke
				(width 0.1)
				(type default)
			)
			(layer "B.Fab")
		)
		(fp_line
			(start -0.508 -0.3048)
			(end -0.508 0.3048)
			(stroke
				(width 0.1)
				(type default)
			)
			(layer "B.Fab")
		)
		(fp_line
			(start 0.508 0.3048)
			(end 0.508 -0.3048)
			(stroke
				(width 0.1)
				(type default)
			)
			(layer "B.Fab")
		)
		(fp_line
			(start -0.508 0.3048)
			(end 0.508 0.3048)
			(stroke
				(width 0.1)
				(type default)
			)
			(layer "B.Fab")
		)
		(pad "1" smd circle
			(at 0.500126 0 270)
			(size 0.635 0.635)
			(layers "B.Cu" "B.Mask" "B.Paste")
			(net "XP3R3V_FPGA")
		)
		(pad "2" smd circle
			(at -0.500126 0 270)
			(size 0.635 0.635)
			(layers "B.Cu" "B.Mask" "B.Paste")
			(net "SG")
		)
	)
	(footprint ""
		(layer "B.Cu")
		(at 95.631 -85.598)
		(property "Reference" "R201"
			(at -0.254 -5.54863 0)
			(unlocked yes)
			(layer "B.SilkS")
			(effects
				(font
					(size 0.7874 0.5842)
					(thickness 0.1524)
				)
				(justify mirror)
			)
		)
		(property "Value" "VAL*"
			(at -0.02032 2.13233 0)
			(unlocked yes)
			(layer "B.Fab")
			(hide yes)
			(effects
				(font
					(size 0.7874 0.5842)
					(thickness 0.1524)
				)
				(justify mirror)
			)
		)
		(property "Tolerance" "TOL*"
			(at -0.044704 3.05435 0)
			(unlocked yes)
			(layer "Cmts.User")
			(hide yes)
			(effects
				(font
					(size 0.7874 0.5842)
					(thickness 0.1524)
				)
				(justify mirror)
			)
		)
		(property "User Part Number" "PARTNUM*"
			(at -0.02032 4.024884 0)
			(unlocked yes)
			(layer "Cmts.User")
			(hide yes)
			(effects
				(font
					(size 0.7874 0.5842)
					(thickness 0.1524)
				)
				(justify mirror)
			)
		)
		(property "Device Type" "RESISTOR-G155-14701-01,4.7KOHMA"
			(at -0.008382 1.210564 0)
			(unlocked yes)
			(layer "B.Fab")
			(hide yes)
			(effects
				(font
					(size 0.7874 0.5842)
					(thickness 0.1524)
				)
				(justify mirror)
			)
		)
		(duplicate_pad_numbers_are_jumpers no)
		(fp_line
			(start -1.143 -0.5588)
			(end 1.143 -0.5588)
			(stroke
				(width 0.1)
				(type default)
			)
			(layer "B.SilkS")
		)
		(fp_line
			(start -1.143 0.5588)
			(end -1.143 -0.5588)
			(stroke
				(width 0.1)
				(type default)
			)
			(layer "B.SilkS")
		)
		(fp_line
			(start 1.143 -0.5588)
			(end 1.143 0.5588)
			(stroke
				(width 0.1)
				(type default)
			)
			(layer "B.SilkS")
		)
		(fp_line
			(start 1.143 0.5588)
			(end -1.143 0.5588)
			(stroke
				(width 0.1)
				(type default)
			)
			(layer "B.SilkS")
		)
		(fp_rect
			(start -1.143 0.5588)
			(end 1.143 -0.5588)
			(stroke
				(width 0)
				(type default)
			)
			(fill no)
			(layer "B.CrtYd")
		)
		(fp_line
			(start -0.508 -0.3048)
			(end 0.508 -0.3048)
			(stroke
				(width 0.1)
				(type default)
			)
			(layer "B.Fab")
		)
		(fp_line
			(start -0.508 0.3048)
			(end -0.508 -0.3048)
			(stroke
				(width 0.1)
				(type default)
			)
			(layer "B.Fab")
		)
		(fp_line
			(start 0.508 -0.3048)
			(end 0.508 0.3048)
			(stroke
				(width 0.1)
				(type default)
			)
			(layer "B.Fab")
		)
		(fp_line
			(start 0.508 0.3048)
			(end -0.508 0.3048)
			(stroke
				(width 0.1)
				(type default)
			)
			(layer "B.Fab")
		)
		(pad "1" smd rect
			(at 0.5334 0 180)
			(size 0.7112 0.6096)
			(layers "B.Cu" "B.Mask" "B.Paste")
			(net "UNNAMED_127_MT25QL128ABA1ESES_3")
		)
		(pad "2" smd rect
			(at -0.5334 0 180)
			(size 0.7112 0.6096)
			(layers "B.Cu" "B.Mask" "B.Paste")
			(net "XP3R3V_FPGA")
		)
		(zone
			(layer "B.Cu")
			(hatch none 0.5)
			(connect_pads
				(clearance 0)
			)
			(min_thickness 0.25)
			(keepout
				(tracks allowed)
				(vias not_allowed)
				(pads allowed)
				(copperpour not_allowed)
				(footprints allowed)
			)
			(placement
				(enabled no)
				(sheetname "")
			)
			(fill
				(thermal_gap 0.5)
				(thermal_bridge_width 0.5)
				(island_removal_mode 0)
			)
			(polygon
				(pts
					(xy 95.5548 -85.2932) (xy 95.7072 -85.2932) (xy 95.7072 -85.9028) (xy 95.5548 -85.9028)
				)
			)
		)
	)
	(footprint ""
		(layer "B.Cu")
		(at 124.587 -50.165)
		(property "Reference" "R265"
			(at 3.302 0.03937 0)
			(unlocked yes)
			(layer "B.SilkS")
			(effects
				(font
					(size 0.7874 0.5842)
					(thickness 0.1524)
				)
				(justify mirror)
			)
		)
		(property "Value" "VAL*"
			(at -0.02032 2.13233 0)
			(unlocked yes)
			(layer "B.Fab")
			(hide yes)
			(effects
				(font
					(size 0.7874 0.5842)
					(thickness 0.1524)
				)
				(justify mirror)
			)
		)
		(property "Device Type" "RESISTOR-G155-11003-01,100KOHMA"
			(at -0.008382 1.210564 0)
			(unlocked yes)
			(layer "B.Fab")
			(hide yes)
			(effects
				(font
					(size 0.7874 0.5842)
					(thickness 0.1524)
				)
				(justify mirror)
			)
		)
		(property "User Part Number" "PARTNUM*"
			(at -0.02032 4.024884 0)
			(unlocked yes)
			(layer "Cmts.User")
			(hide yes)
			(effects
				(font
					(size 0.7874 0.5842)
					(thickness 0.1524)
				)
				(justify mirror)
			)
		)
		(property "Tolerance" "TOL*"
			(at -0.044704 3.05435 0)
			(unlocked yes)
			(layer "Cmts.User")
			(hide yes)
			(effects
				(font
					(size 0.7874 0.5842)
					(thickness 0.1524)
				)
				(justify mirror)
			)
		)
		(duplicate_pad_numbers_are_jumpers no)
		(fp_line
			(start -1.143 -0.5588)
			(end 1.143 -0.5588)
			(stroke
				(width 0.1)
				(type default)
			)
			(layer "B.SilkS")
		)
		(fp_line
			(start -1.143 0.5588)
			(end -1.143 -0.5588)
			(stroke
				(width 0.1)
				(type default)
			)
			(layer "B.SilkS")
		)
		(fp_line
			(start 1.143 -0.5588)
			(end 1.143 0.5588)
			(stroke
				(width 0.1)
				(type default)
			)
			(layer "B.SilkS")
		)
		(fp_line
			(start 1.143 0.5588)
			(end -1.143 0.5588)
			(stroke
				(width 0.1)
				(type default)
			)
			(layer "B.SilkS")
		)
		(fp_rect
			(start -1.143 -0.5588)
			(end 1.143 0.5588)
			(stroke
				(width 0)
				(type default)
			)
			(fill no)
			(layer "B.CrtYd")
		)
		(fp_line
			(start -0.508 -0.3048)
			(end 0.508 -0.3048)
			(stroke
				(width 0.1)
				(type default)
			)
			(layer "B.Fab")
		)
		(fp_line
			(start -0.508 0.3048)
			(end -0.508 -0.3048)
			(stroke
				(width 0.1)
				(type default)
			)
			(layer "B.Fab")
		)
		(fp_line
			(start 0.508 -0.3048)
			(end 0.508 0.3048)
			(stroke
				(width 0.1)
				(type default)
			)
			(layer "B.Fab")
		)
		(fp_line
			(start 0.508 0.3048)
			(end -0.508 0.3048)
			(stroke
				(width 0.1)
				(type default)
			)
			(layer "B.Fab")
		)
		(pad "1" smd rect
			(at 0.5334 0 180)
			(size 0.7112 0.6096)
			(layers "B.Cu" "B.Mask" "B.Paste")
			(net "XP3R3V_FPGA")
		)
		(pad "2" smd rect
			(at -0.5334 0 180)
			(size 0.7112 0.6096)
			(layers "B.Cu" "B.Mask" "B.Paste")
			(net "UART_MAC_TX_FPGA_RX")
		)
		(zone
			(layer "B.Cu")
			(hatch none 0.5)
			(connect_pads
				(clearance 0)
			)
			(min_thickness 0.25)
			(keepout
				(tracks allowed)
				(vias not_allowed)
				(pads allowed)
				(copperpour not_allowed)
				(footprints allowed)
			)
			(placement
				(enabled no)
				(sheetname "")
			)
			(fill
				(thermal_gap 0.5)
				(thermal_bridge_width 0.5)
				(island_removal_mode 0)
			)
			(polygon
				(pts
					(xy 124.5108 -50.4698) (xy 124.5108 -49.8602) (xy 124.6632 -49.8602) (xy 124.6632 -50.4698)
				)
			)
		)
		(zone
			(layer "B.Cu")
			(hatch none 0.5)
			(connect_pads
				(clearance 0)
			)
			(min_thickness 0.25)
			(keepout
				(tracks not_allowed)
				(vias allowed)
				(pads allowed)
				(copperpour not_allowed)
				(footprints allowed)
			)
			(placement
				(enabled no)
				(sheetname "")
			)
			(fill
				(thermal_gap 0.5)
				(thermal_bridge_width 0.5)
				(island_removal_mode 0)
			)
			(polygon
				(pts
					(xy 124.5108 -50.4698) (xy 124.5108 -49.8602) (xy 124.6632 -49.8602) (xy 124.6632 -50.4698)
				)
			)
		)
	)
)
